# T6G (Grand Teton) — schematic netlist excerpt (pin names and nets, part order shuffled) for the footprints in the layout excerpt that follows; sources: Cadence DE-HDL packaged netlist, KiCad conversion of 04192023_DAF0TMB3IC0_F0TG_MB_C_brd_V02_OCP.brd

R3147  Q_RES  1K 1% CHIP  pkg 0402LF  page 140 : A = P3V3_AUX ; B = HP_LVC3_OCP_V3_2_PRSNT2_PLD_N
PC150_6  Q_CAP  0.1UF 25V 10% X7R  pkg 0402  page 196 : A = PVDDCR_CPU0_P0_VCCS ; B = GND

(kicad_pcb
	(version 20260206)
	(generator "pcbnew")
	(generator_version "10.0")
	(general
		(thickness 1.6)
		(legacy_teardrops no)
	)
	(paper "A4")
	(title_block
		(title "04192023_DAF0TMB3IC0_F0TG_MB_C_brd_V02_OCP.brd")
		(comment 1 "Grand Teton / footprints 1478-1479 of 8354")
	)
	(layers
		(0 "F.Cu" signal "TOP")
		(4 "In1.Cu" signal "GND")
		(6 "In2.Cu" signal "IN1")
		(8 "In3.Cu" signal "GND1")
		(10 "In4.Cu" signal "IN2")
		(12 "In5.Cu" signal "GND2")
		(14 "In6.Cu" signal "IN3")
		(16 "In7.Cu" signal "GND3")
		(18 "In8.Cu" signal "VCC")
		(20 "In9.Cu" signal "VCC1")
		(22 "In10.Cu" signal "GND4")
		(24 "In11.Cu" signal "IN4")
		(26 "In12.Cu" signal "GND5")
		(28 "In13.Cu" signal "IN5")
		(30 "In14.Cu" signal "GND6")
		(32 "In15.Cu" signal "IN6")
		(34 "In16.Cu" signal "GND7")
		(2 "B.Cu" signal "BOTTOM")
		(9 "F.Adhes" user "F.Adhesive")
		(11 "B.Adhes" user "B.Adhesive")
		(13 "F.Paste" user "Package Geometry/Pastemask Top")
		(15 "B.Paste" user "Package Geometry/Pastemask Bottom")
		(5 "F.SilkS" user "Ref Des/Silkscreen Top")
		(7 "B.SilkS" user "Ref Des/Silkscreen Bottom")
		(1 "F.Mask" user "Board Geometry/Soldermask Top")
		(3 "B.Mask" user "Board Geometry/Soldermask Bottom")
		(17 "Dwgs.User" user "User.Drawings")
		(19 "Cmts.User" user "User.Comments")
		(21 "Eco1.User" user "User.Eco1")
		(23 "Eco2.User" user "User.Eco2")
		(25 "Edge.Cuts" user "Board Geometry/Outline")
		(27 "Margin" user)
		(31 "F.CrtYd" user "Package Geometry/Place Bound Top")
		(29 "B.CrtYd" user "Package Geometry/Place Bound Bottom")
		(35 "F.Fab" user "Ref Des/Assembly Top")
		(33 "B.Fab" user "Ref Des/Assembly Bottom")
	)
	(footprint ""
		(layer "F.Cu")
		(at 350.421702 -156.281882 -90)
		(property "Reference" "PC150_6"
			(at 0 0 270)
			(layer "F.SilkS")
			(hide yes)
			(effects
				(font
					(size 1.27 1.27)
				)
			)
		)
		(property "Value" ""
			(at 0 0 270)
			(layer "F.Fab")
			(effects
				(font
					(size 1.27 1.27)
				)
			)
		)
		(duplicate_pad_numbers_are_jumpers no)
		(fp_line
			(start -0.7874 0.4064)
			(end -0.7874 -0.4064)
			(stroke
				(width 0.1524)
				(type default)
			)
			(layer "F.SilkS")
		)
		(fp_line
			(start 0.7874 0.4064)
			(end -0.7874 0.4064)
			(stroke
				(width 0.1524)
				(type default)
			)
			(layer "F.SilkS")
		)
		(fp_line
			(start -0.7874 -0.4064)
			(end 0.7874 -0.4064)
			(stroke
				(width 0.1524)
				(type default)
			)
			(layer "F.SilkS")
		)
		(fp_line
			(start 0.7874 -0.4064)
			(end 0.7874 0.4064)
			(stroke
				(width 0.1524)
				(type default)
			)
			(layer "F.SilkS")
		)
		(fp_line
			(start -0.67945 0.3048)
			(end -0.67945 -0.305054)
			(stroke
				(width 0.1)
				(type default)
			)
			(layer "F.Fab")
		)
		(fp_line
			(start -0.12065 0.3048)
			(end -0.67945 0.3048)
			(stroke
				(width 0.1)
				(type default)
			)
			(layer "F.Fab")
		)
		(fp_line
			(start 0.120396 0.3048)
			(end 0.120396 0.2794)
			(stroke
				(width 0.1)
				(type default)
			)
			(layer "F.Fab")
		)
		(fp_line
			(start 0.67945 0.3048)
			(end 0.120396 0.3048)
			(stroke
				(width 0.1)
				(type default)
			)
			(layer "F.Fab")
		)
		(fp_line
			(start -0.12065 0.2794)
			(end -0.12065 0.3048)
			(stroke
				(width 0.1)
				(type default)
			)
			(layer "F.Fab")
		)
		(fp_line
			(start 0.120396 0.2794)
			(end -0.12065 0.2794)
			(stroke
				(width 0.1)
				(type default)
			)
			(layer "F.Fab")
		)
		(fp_line
			(start -0.12065 -0.2794)
			(end 0.12065 -0.2794)
			(stroke
				(width 0.1)
				(type default)
			)
			(layer "F.Fab")
		)
		(fp_line
			(start 0.12065 -0.2794)
			(end 0.12065 -0.3048)
			(stroke
				(width 0.1)
				(type default)
			)
			(layer "F.Fab")
		)
		(fp_line
			(start 0.12065 -0.3048)
			(end 0.67945 -0.3048)
			(stroke
				(width 0.1)
				(type default)
			)
			(layer "F.Fab")
		)
		(fp_line
			(start 0.67945 -0.3048)
			(end 0.67945 0.3048)
			(stroke
				(width 0.1)
				(type default)
			)
			(layer "F.Fab")
		)
		(fp_line
			(start -0.67945 -0.305054)
			(end -0.12065 -0.305054)
			(stroke
				(width 0.1)
				(type default)
			)
			(layer "F.Fab")
		)
		(fp_line
			(start -0.12065 -0.305054)
			(end -0.12065 -0.2794)
			(stroke
				(width 0.1)
				(type default)
			)
			(layer "F.Fab")
		)
		(pad "1" smd circle
			(at -0.40005 0 270)
			(size 0 0)
			(layers "F.Cu" "F.Mask" "F.Paste")
			(net "PVDDCR_CPU0_P0_VCCS")
		)
		(pad "2" smd circle
			(at 0.40005 0 270)
			(size 0 0)
			(layers "F.Cu" "F.Mask" "F.Paste")
			(net "GND")
		)
	)
	(footprint ""
		(layer "F.Cu")
		(at 15.58417 -69.178678)
		(property "Reference" "R3147"
			(at 0 0 0)
			(layer "F.SilkS")
			(hide yes)
			(effects
				(font
					(size 1.27 1.27)
				)
			)
		)
		(property "Value" ""
			(at 0 0 0)
			(layer "F.Fab")
			(effects
				(font
					(size 1.27 1.27)
				)
			)
		)
		(duplicate_pad_numbers_are_jumpers no)
		(fp_line
			(start -0.7874 -0.4064)
			(end 0.7874 -0.4064)
			(stroke
				(width 0.1524)
				(type default)
			)
			(layer "F.SilkS")
		)
		(fp_line
			(start -0.7874 0.4064)
			(end -0.7874 -0.4064)
			(stroke
				(width 0.1524)
				(type default)
			)
			(layer "F.SilkS")
		)
		(fp_line
			(start 0.7874 -0.4064)
			(end 0.7874 0.4064)
			(stroke
				(width 0.1524)
				(type default)
			)
			(layer "F.SilkS")
		)
		(fp_line
			(start 0.7874 0.4064)
			(end -0.7874 0.4064)
			(stroke
				(width 0.1524)
				(type default)
			)
			(layer "F.SilkS")
		)
		(fp_line
			(start -0.67945 -0.305054)
			(end -0.12065 -0.305054)
			(stroke
				(width 0.1)
				(type default)
			)
			(layer "F.Fab")
		)
		(fp_line
			(start -0.67945 0.3048)
			(end -0.67945 -0.305054)
			(stroke
				(width 0.1)
				(type default)
			)
			(layer "F.Fab")
		)
		(fp_line
			(start -0.12065 -0.305054)
			(end -0.12065 -0.2794)
			(stroke
				(width 0.1)
				(type default)
			)
			(layer "F.Fab")
		)
		(fp_line
			(start -0.12065 -0.2794)
			(end 0.12065 -0.2794)
			(stroke
				(width 0.1)
				(type default)
			)
			(layer "F.Fab")
		)
		(fp_line
			(start -0.12065 0.2794)
			(end -0.12065 0.3048)
			(stroke
				(width 0.1)
				(type default)
			)
			(layer "F.Fab")
		)
		(fp_line
			(start -0.12065 0.3048)
			(end -0.67945 0.3048)
			(stroke
				(width 0.1)
				(type default)
			)
			(layer "F.Fab")
		)
		(fp_line
			(start 0.120396 0.2794)
			(end -0.12065 0.2794)
			(stroke
				(width 0.1)
				(type default)
			)
			(layer "F.Fab")
		)
		(fp_line
			(start 0.120396 0.3048)
			(end 0.120396 0.2794)
			(stroke
				(width 0.1)
				(type default)
			)
			(layer "F.Fab")
		)
		(fp_line
			(start 0.12065 -0.3048)
			(end 0.67945 -0.3048)
			(stroke
				(width 0.1)
				(type default)
			)
			(layer "F.Fab")
		)
		(fp_line
			(start 0.12065 -0.2794)
			(end 0.12065 -0.3048)
			(stroke
				(width 0.1)
				(type default)
			)
			(layer "F.Fab")
		)
		(fp_line
			(start 0.67945 -0.3048)
			(end 0.67945 0.3048)
			(stroke
				(width 0.1)
				(type default)
			)
			(layer "F.Fab")
		)
		(fp_line
			(start 0.67945 0.3048)
			(end 0.120396 0.3048)
			(stroke
				(width 0.1)
				(type default)
			)
			(layer "F.Fab")
		)
		(pad "1" smd circle
			(at -0.40005 0)
			(size 0 0)
			(layers "F.Cu" "F.Mask" "F.Paste")
			(net "P3V3_AUX")
		)
		(pad "2" smd circle
			(at 0.40005 0)
			(size 0 0)
			(layers "F.Cu" "F.Mask" "F.Paste")
			(net "HP_LVC3_OCP_V3_2_PRSNT2_PLD_N")
		)
	)
)
